(kicad_pcb
	(version 20221018)
	(generator pcbnew)
	(general
    (thickness 1.62)
  )
	(paper "A4")
	(title_block
    (title "ECP5 - Datacenter Secure Control Module (DC-SCM)")
    (date "2024-07-01")
    (rev "1.2.1")
		(comment 9 "footprints 64-68 of 506")
	)
	(layers
    (0 "F.Cu" signal)
    (1 "In1.Cu" power)
    (2 "In2.Cu" signal)
    (3 "In3.Cu" power)
    (4 "In4.Cu" power)
    (5 "In5.Cu" signal)
    (6 "In6.Cu" power)
    (31 "B.Cu" signal)
    (32 "B.Adhes" user "B.Adhesive")
    (33 "F.Adhes" user "F.Adhesive")
    (34 "B.Paste" user)
    (35 "F.Paste" user)
    (36 "B.SilkS" user "B.Silkscreen")
    (37 "F.SilkS" user "F.Silkscreen")
    (38 "B.Mask" user)
    (39 "F.Mask" user)
    (40 "Dwgs.User" user "User.Drawings")
    (41 "Cmts.User" user "User.Comments")
    (42 "Eco1.User" user "User.Eco1")
    (43 "Eco2.User" user "User.Eco2")
    (44 "Edge.Cuts" user)
    (45 "Margin" user)
    (46 "B.CrtYd" user "B.Courtyard")
    (47 "F.CrtYd" user "F.Courtyard")
    (48 "B.Fab" user)
    (49 "F.Fab" user)
  )
	(footprint "antmicro-footprints:QFN-32-1EP_5x5mm" locked (layer "F.Cu")
    (at 125.034 115.794 -90)
    (property "Author" "Antmicro")
    (property "License" "Apache-2.0")
    (property "MPN" "USB3300-EZK-TR")
    (property "Manufacturer" "Microchip Technology")
    (property "Sheetfile" "interfaces.kicad_sch")
    (property "Sheetname" "Interfaces")
    (property "ki_description" "USB Interface, USB Host Controller, USB 2.0 OTG, 3 V, 3.6 V, VQFN, 32 Pins")
    (property "ki_keywords" "SMT, INTERFACE, CONTROLLER, IC, USB")
    (attr smd)
    (fp_text reference "U9" (at -3.469 -3.036 90) (layer "F.SilkS")
        (effects (font (size 0.7 0.7) (thickness 0.12051)))
    )
    (fp_text value "USB3300-EZK-TR" (at 3.23987 3.520501 90) (layer "F.Fab")
        (effects (font (size 0.482094 0.482094) (thickness 0.015)))
    )
    (fp_text user "License: Apache-2.0" (at -4.939 5.91 -90) (layer "F.Fab") hide
        (effects (font (size 0.7 0.7) (thickness 0.15)) (justify left bottom))
    )
    (fp_text user "Author: Antmicro" (at -4.939 8.31 -90) (layer "F.Fab") hide
        (effects (font (size 0.7 0.7) (thickness 0.15)) (justify left bottom))
    )
    (fp_text user "${REFERENCE}" (at -4.939 7.11 -90) (layer "F.Fab") hide
        (effects (font (size 0.7 0.7) (thickness 0.15)) (justify left bottom))
    )
    (fp_rect (start -1.446 -0.175) (end -0.246 -1.375)
      (stroke (width 0.2) (type solid)) (fill solid) (layer "F.Paste"))
    (fp_rect (start -1.446 1.474) (end -0.246 0.274)
      (stroke (width 0.2) (type solid)) (fill solid) (layer "F.Paste"))
    (fp_rect (start 0.203 -0.175) (end 1.403 -1.375)
      (stroke (width 0.2) (type solid)) (fill solid) (layer "F.Paste"))
    (fp_rect (start 0.203 1.474) (end 1.403 0.274)
      (stroke (width 0.2) (type solid)) (fill solid) (layer "F.Paste"))
    (fp_line (start -2.62 2.648) (end -2.62 2.249)
      (stroke (width 0.15) (type solid)) (layer "F.SilkS"))
    (fp_line (start -2.221 -2.551) (end -2.62 -2.149)
      (stroke (width 0.15) (type solid)) (layer "F.SilkS"))
    (fp_line (start -2.221 2.648) (end -2.62 2.648)
      (stroke (width 0.15) (type solid)) (layer "F.SilkS"))
    (fp_line (start 2.581 -2.551) (end 2.178 -2.551)
      (stroke (width 0.15) (type solid)) (layer "F.SilkS"))
    (fp_line (start 2.581 -2.551) (end 2.581 -2.149)
      (stroke (width 0.15) (type solid)) (layer "F.SilkS"))
    (fp_line (start 2.581 2.249) (end 2.581 2.648)
      (stroke (width 0.15) (type solid)) (layer "F.SilkS"))
    (fp_line (start 2.581 2.648) (end 2.178 2.648)
      (stroke (width 0.15) (type solid)) (layer "F.SilkS"))
    (fp_circle (center -3.25 -1.702) (end -3.2 -1.702)
      (stroke (width 0.15) (type solid)) (fill solid) (layer "F.SilkS"))
    (fp_rect (start -2.74 -2.75) (end 2.75 2.74)
      (stroke (width 0.05) (type solid)) (fill none) (layer "F.CrtYd"))
    (fp_line (start -2.499 -2.299) (end -2.298 -2.5)
      (stroke (width 0.15) (type solid)) (layer "F.Fab"))
    (fp_rect (start -2.499 -2.5) (end 2.5 2.499)
      (stroke (width 0.15) (type solid)) (fill none) (layer "F.Fab"))
    (pad "1" smd rect locked (at -2.495 -1.702 180) (size 0.28 0.85) (layers "F.Cu" "F.Paste" "F.Mask")
      (net 1 "GND") (pinfunction "GND") (pintype "power_in") (solder_mask_margin 0.07))
    (pad "2" smd rect locked (at -2.495 -1.2 180) (size 0.28 0.85) (layers "F.Cu" "F.Paste" "F.Mask")
      (net 1 "GND") (pinfunction "GND") (pintype "passive") (solder_mask_margin 0.07))
    (pad "3" smd rect locked (at -2.495 -0.701 180) (size 0.28 0.85) (layers "F.Cu" "F.Paste" "F.Mask")
      (net 500 "unconnected-(U9-CPEN-Pad3)") (pinfunction "CPEN") (pintype "output+no_connect") (solder_mask_margin 0.07))
    (pad "4" smd rect locked (at -2.495 -0.201 180) (size 0.28 0.85) (layers "F.Cu" "F.Paste" "F.Mask")
      (net 406 "Net-(U9-VBUS)") (pinfunction "VBUS") (pintype "bidirectional") (solder_mask_margin 0.07))
    (pad "5" smd rect locked (at -2.495 0.296 180) (size 0.28 0.85) (layers "F.Cu" "F.Paste" "F.Mask")
      (net 501 "unconnected-(U9-ID-Pad5)") (pinfunction "ID") (pintype "input+no_connect") (solder_mask_margin 0.07))
    (pad "6" smd rect locked (at -2.495 0.8 180) (size 0.28 0.85) (layers "F.Cu" "F.Paste" "F.Mask")
      (net 2 "VCC3V3") (pinfunction "VDD3.3") (pintype "power_in") (solder_mask_margin 0.07))
    (pad "7" smd rect locked (at -2.495 1.3 180) (size 0.28 0.85) (layers "F.Cu" "F.Paste" "F.Mask")
      (net 100 "USB1_DP") (pinfunction "DP") (pintype "bidirectional") (solder_mask_margin 0.07))
    (pad "8" smd rect locked (at -2.495 1.8 180) (size 0.28 0.85) (layers "F.Cu" "F.Paste" "F.Mask")
      (net 101 "USB1_DN") (pinfunction "DM") (pintype "bidirectional") (solder_mask_margin 0.07))
    (pad "9" smd rect locked (at -1.768 2.523 180) (size 0.85 0.28) (layers "F.Cu" "F.Paste" "F.Mask")
      (net 330 "ULPI1_RESET") (pinfunction "RESET") (pintype "input") (solder_mask_margin 0.07))
    (pad "10" smd rect locked (at -1.269 2.523 180) (size 0.85 0.28) (layers "F.Cu" "F.Paste" "F.Mask")
      (net 502 "unconnected-(U9-EXTVBUS-Pad10)") (pinfunction "EXTVBUS") (pintype "input+no_connect") (solder_mask_margin 0.07))
    (pad "11" smd rect locked (at -0.772 2.523 180) (size 0.85 0.28) (layers "F.Cu" "F.Paste" "F.Mask")
      (net 331 "ULPI1_NXT") (pinfunction "NXT") (pintype "output") (solder_mask_margin 0.07))
    (pad "12" smd rect locked (at -0.272 2.523 180) (size 0.85 0.28) (layers "F.Cu" "F.Paste" "F.Mask")
      (net 332 "ULPI1_DIR") (pinfunction "DIR") (pintype "output") (solder_mask_margin 0.07))
    (pad "13" smd rect locked (at 0.229 2.523 180) (size 0.85 0.28) (layers "F.Cu" "F.Paste" "F.Mask")
      (net 333 "ULPI1_STP") (pinfunction "STP") (pintype "input") (solder_mask_margin 0.07))
    (pad "14" smd rect locked (at 0.728 2.523 180) (size 0.85 0.28) (layers "F.Cu" "F.Paste" "F.Mask")
      (net 334 "ULPI1_CLKO") (pinfunction "CLKOUT") (pintype "output") (solder_mask_margin 0.07))
    (pad "15" smd rect locked (at 1.23 2.523 180) (size 0.85 0.28) (layers "F.Cu" "F.Paste" "F.Mask")
      (net 672 "Net-(C76-Pad2)") (pinfunction "VDD1.8") (pintype "power_in") (solder_mask_margin 0.07))
    (pad "16" smd rect locked (at 1.73 2.523 180) (size 0.85 0.28) (layers "F.Cu" "F.Paste" "F.Mask")
      (net 2 "VCC3V3") (pinfunction "VDD3.3") (pintype "passive") (solder_mask_margin 0.07))
    (pad "17" smd rect locked (at 2.456 1.8 180) (size 0.28 0.85) (layers "F.Cu" "F.Paste" "F.Mask")
      (net 335 "ULPI1_D7") (pinfunction "DATA[7]") (pintype "bidirectional") (solder_mask_margin 0.07))
    (pad "18" smd rect locked (at 2.456 1.3 180) (size 0.28 0.85) (layers "F.Cu" "F.Paste" "F.Mask")
      (net 336 "ULPI1_D6") (pinfunction "DATA[6]") (pintype "bidirectional") (solder_mask_margin 0.07))
    (pad "19" smd rect locked (at 2.456 0.8 180) (size 0.28 0.85) (layers "F.Cu" "F.Paste" "F.Mask")
      (net 337 "ULPI1_D5") (pinfunction "DATA[5]") (pintype "bidirectional") (solder_mask_margin 0.07))
    (pad "20" smd rect locked (at 2.456 0.296 180) (size 0.28 0.85) (layers "F.Cu" "F.Paste" "F.Mask")
      (net 338 "ULPI1_D4") (pinfunction "DATA[4]") (pintype "bidirectional") (solder_mask_margin 0.07))
    (pad "21" smd rect locked (at 2.456 -0.201 180) (size 0.28 0.85) (layers "F.Cu" "F.Paste" "F.Mask")
      (net 339 "ULPI1_D3") (pinfunction "DATA[3]") (pintype "bidirectional") (solder_mask_margin 0.07))
    (pad "22" smd rect locked (at 2.456 -0.701 180) (size 0.28 0.85) (layers "F.Cu" "F.Paste" "F.Mask")
      (net 340 "ULPI1_D2") (pinfunction "DATA[2]") (pintype "bidirectional") (solder_mask_margin 0.07))
    (pad "23" smd rect locked (at 2.456 -1.2 180) (size 0.28 0.85) (layers "F.Cu" "F.Paste" "F.Mask")
      (net 341 "ULPI1_D1") (pinfunction "DATA[1]") (pintype "bidirectional") (solder_mask_margin 0.07))
    (pad "24" smd rect locked (at 2.456 -1.702 180) (size 0.28 0.85) (layers "F.Cu" "F.Paste" "F.Mask")
      (net 342 "ULPI1_D0") (pinfunction "DATA[0]") (pintype "bidirectional") (solder_mask_margin 0.07))
    (pad "25" smd rect locked (at 1.73 -2.426 180) (size 0.85 0.28) (layers "F.Cu" "F.Paste" "F.Mask")
      (net 2 "VCC3V3") (pinfunction "VDD3.3") (pintype "passive") (solder_mask_margin 0.07))
    (pad "26" smd rect locked (at 1.23 -2.426 180) (size 0.85 0.28) (layers "F.Cu" "F.Paste" "F.Mask")
      (net 672 "Net-(C76-Pad2)") (pinfunction "VDD1.8") (pintype "passive") (solder_mask_margin 0.07))
    (pad "27" smd rect locked (at 0.728 -2.426 180) (size 0.85 0.28) (layers "F.Cu" "F.Paste" "F.Mask")
      (net 503 "unconnected-(U9-XO-Pad27)") (pinfunction "XO") (pintype "output+no_connect") (solder_mask_margin 0.07))
    (pad "28" smd rect locked (at 0.229 -2.426 180) (size 0.85 0.28) (layers "F.Cu" "F.Paste" "F.Mask")
      (net 679 "/Interfaces/USB1_CLK") (pinfunction "XI") (pintype "input") (solder_mask_margin 0.07))
    (pad "29" smd rect locked (at -0.272 -2.426 180) (size 0.85 0.28) (layers "F.Cu" "F.Paste" "F.Mask")
      (net 226 "Net-(U9-VDDA1.8)") (pinfunction "VDDA1.8") (pintype "power_in") (solder_mask_margin 0.07))
    (pad "30" smd rect locked (at -0.772 -2.426 180) (size 0.85 0.28) (layers "F.Cu" "F.Paste" "F.Mask")
      (net 2 "VCC3V3") (pinfunction "VDD3.3") (pintype "passive") (solder_mask_margin 0.07))
    (pad "31" smd rect locked (at -1.269 -2.426 180) (size 0.85 0.28) (layers "F.Cu" "F.Paste" "F.Mask")
      (net 2 "VCC3V3") (pinfunction "REG_EN") (pintype "bidirectional") (solder_mask_margin 0.07))
    (pad "32" smd rect locked (at -1.768 -2.426 180) (size 0.85 0.28) (layers "F.Cu" "F.Paste" "F.Mask")
      (net 407 "Net-(U9-RBIAS)") (pinfunction "RBIAS") (pintype "bidirectional") (solder_mask_margin 0.07))
    (pad "33" smd rect locked (at -0.02 0.048 180) (size 3.45 3.45) (layers "F.Cu" "F.Mask")
      (net 1 "GND") (pinfunction "EP") (pintype "passive"))
  )
	(footprint "antmicro-footprints:R_0402_1005Metric" (layer "F.Cu")
    (at 129.3 113.65 -90)
    (descr "Resistor SMD 0402")
    (tags "resistor SMD 0402")
    (property "Author" "Antmicro")
    (property "License" "Apache-2.0")
    (property "MPN" "CR0402-FX-1202GLF")
    (property "Manufacturer" "Bourns")
    (property "Public" "False")
    (property "Sheetfile" "interfaces.kicad_sch")
    (property "Sheetname" "Interfaces")
    (property "Tolerance" "1%")
    (property "Val" "12k")
    (property "ki_description" "SMD Chip Resistor, 12 kohm, ± 1%, 62.5 mW, 0402 [1005 Metric], Thick Film, General Purpose")
    (property "ki_keywords" "0402, SMT, RESISTOR, PASSIVE")
    (attr smd)
    (fp_text reference "R77" (at -2.61 0.02 90) (layer "F.SilkS")
        (effects (font (size 0.7 0.7) (thickness 0.127)))
    )
    (fp_text value "R_12k_0402" (at 0 1.17 90) (layer "F.Fab")
        (effects (font (size 1 1) (thickness 0.15)))
    )
    (fp_text user "Author: Antmicro" (at -0.95 4.169 -90) (layer "F.Fab") hide
        (effects (font (size 0.7 0.7) (thickness 0.15)) (justify left bottom))
    )
    (fp_text user "${REFERENCE}" (at 0 0 90) (layer "F.Fab")
        (effects (font (size 0.25 0.25) (thickness 0.04)))
    )
    (fp_text user "License: Apache-2.0" (at -0.95 5.169 -90) (layer "F.Fab") hide
        (effects (font (size 0.7 0.7) (thickness 0.15)) (justify left bottom))
    )
    (fp_rect (start -0.925 -0.47) (end 0.925 0.47)
      (stroke (width 0.05) (type default)) (fill none) (layer "F.CrtYd"))
    (fp_rect (start -0.5 -0.25) (end 0.5 0.25)
      (stroke (width 0.15) (type solid)) (fill none) (layer "F.Fab"))
    (pad "1" smd roundrect (at -0.48 0 270) (size 0.59 0.64) (layers "F.Cu" "F.Paste" "F.Mask") (roundrect_rratio 0.25)
      (net 1 "GND") (pintype "passive"))
    (pad "2" smd roundrect (at 0.48 0 270) (size 0.59 0.64) (layers "F.Cu" "F.Paste" "F.Mask") (roundrect_rratio 0.25)
      (net 407 "Net-(U9-RBIAS)") (pintype "passive"))
  )
	(footprint "antmicro-footprints:C_0402_1005Metric" (layer "F.Cu")
    (at 135.7 154.9 -90)
    (descr "Capacitor SMD 0402")
    (tags "capacitor SMD 0402")
    (property "Author" "Antmicro")
    (property "Dielectric" "")
    (property "License" "Apache-2.0")
    (property "MPN" "CC0402MRX5R5BB106")
    (property "Manufacturer" "YAGEO")
    (property "Public" "False")
    (property "Sheetfile" "pcie-conn.kicad_sch")
    (property "Sheetname" "PCIe-connector")
    (property "Val" "10u")
    (property "Voltage" "")
    (property "ki_description" "SMD Multilayer Ceramic Capacitor, 10 µF, 6.3 V, 0402 [1005 Metric], ± 20%, X5R, CC Series")
    (property "ki_keywords" "0402, SMT, CAPACITOR, PASSIVE, MLCC, CERAMIC")
    (attr smd)
    (fp_text reference "C41" (at -2.505 0.03 90) (layer "F.SilkS")
        (effects (font (size 0.7 0.7) (thickness 0.127)))
    )
    (fp_text value "C_10u_0402" (at 0 1.17 90) (layer "F.Fab")
        (effects (font (size 1 1) (thickness 0.15)))
    )
    (fp_text user "Author: Antmicro" (at -0.939 3.399 -90) (layer "F.Fab") hide
        (effects (font (size 0.7 0.7) (thickness 0.15)) (justify left bottom))
    )
    (fp_text user "License: Apache-2.0" (at -0.939 5.799 -90) (layer "F.Fab") hide
        (effects (font (size 0.7 0.7) (thickness 0.15)) (justify left bottom))
    )
    (fp_text user "${REFERENCE}" (at 0 0 90) (layer "F.Fab")
        (effects (font (size 0.25 0.25) (thickness 0.04)))
    )
    (fp_rect (start -0.925 -0.47) (end 0.925 0.47)
      (stroke (width 0.05) (type default)) (fill none) (layer "F.CrtYd"))
    (fp_line (start -0.494 -0.25) (end 0.504 -0.25)
      (stroke (width 0.15) (type solid)) (layer "F.Fab"))
    (fp_line (start -0.494 0.248) (end -0.494 -0.25)
      (stroke (width 0.15) (type solid)) (layer "F.Fab"))
    (fp_line (start 0.504 -0.25) (end 0.504 0.248)
      (stroke (width 0.15) (type solid)) (layer "F.Fab"))
    (fp_line (start 0.504 0.248) (end -0.494 0.248)
      (stroke (width 0.15) (type solid)) (layer "F.Fab"))
    (pad "1" smd roundrect (at -0.48 0 270) (size 0.59 0.64) (layers "F.Cu" "F.Paste" "F.Mask") (roundrect_rratio 0.25)
      (net 1 "GND") (pintype "passive"))
    (pad "2" smd roundrect (at 0.48 0 270) (size 0.59 0.64) (layers "F.Cu" "F.Paste" "F.Mask") (roundrect_rratio 0.25)
      (net 2 "VCC3V3") (pintype "passive"))
  )
	(footprint "antmicro-footprints:C_0402_1005Metric" (layer "F.Cu")
    (at 136.525 168.325 -90)
    (descr "Capacitor SMD 0402")
    (tags "capacitor SMD 0402")
    (property "Author" "Antmicro")
    (property "Dielectric" "X5R")
    (property "License" "Apache-2.0")
    (property "MPN" "GRM155R61H104KE14D")
    (property "Manufacturer" "Murata")
    (property "Public" "False")
    (property "Sheetfile" "pcie-conn.kicad_sch")
    (property "Sheetname" "PCIe-connector")
    (property "Val" "100n")
    (property "Voltage" "50V")
    (property "ki_description" "SMD Multilayer Ceramic Capacitor, 0.1 µF, 50 V, 0402 [1005 Metric], ± 10%, X5R, GRM Series")
    (property "ki_keywords" "0402, SMT, CAPACITOR, PASSIVE, CERAMIC, MLCC")
    (attr smd)
    (fp_text reference "C38" (at 2.13 -0.05 90) (layer "F.SilkS")
        (effects (font (size 0.7 0.7) (thickness 0.127)))
    )
    (fp_text value "C_100n_0402" (at 0 1.17 90) (layer "F.Fab")
        (effects (font (size 1 1) (thickness 0.15)))
    )
    (fp_text user "Author: Antmicro" (at -0.939 3.399 -90) (layer "F.Fab") hide
        (effects (font (size 0.7 0.7) (thickness 0.15)) (justify left bottom))
    )
    (fp_text user "${REFERENCE}" (at 0 0 90) (layer "F.Fab")
        (effects (font (size 0.25 0.25) (thickness 0.04)))
    )
    (fp_text user "License: Apache-2.0" (at -0.939 5.799 -90) (layer "F.Fab") hide
        (effects (font (size 0.7 0.7) (thickness 0.15)) (justify left bottom))
    )
    (fp_rect (start -0.925 -0.47) (end 0.925 0.47)
      (stroke (width 0.05) (type default)) (fill none) (layer "F.CrtYd"))
    (fp_line (start -0.494 -0.25) (end 0.504 -0.25)
      (stroke (width 0.15) (type solid)) (layer "F.Fab"))
    (fp_line (start -0.494 0.248) (end -0.494 -0.25)
      (stroke (width 0.15) (type solid)) (layer "F.Fab"))
    (fp_line (start 0.504 -0.25) (end 0.504 0.248)
      (stroke (width 0.15) (type solid)) (layer "F.Fab"))
    (fp_line (start 0.504 0.248) (end -0.494 0.248)
      (stroke (width 0.15) (type solid)) (layer "F.Fab"))
    (pad "1" smd roundrect (at -0.48 0 270) (size 0.59 0.64) (layers "F.Cu" "F.Paste" "F.Mask") (roundrect_rratio 0.25)
      (net 216 "Net-(J2-PET3_N)") (pintype "passive"))
    (pad "2" smd roundrect (at 0.48 0 270) (size 0.59 0.64) (layers "F.Cu" "F.Paste" "F.Mask") (roundrect_rratio 0.25)
      (net 695 "PCIE_HPM_TX3_N") (pintype "passive"))
  )
	(footprint "antmicro-footprints:R_0402_1005Metric" (layer "F.Cu")
    (at 126.1 154.3 -90)
    (descr "Resistor SMD 0402")
    (tags "resistor SMD 0402")
    (property "Author" "Antmicro")
    (property "License" "Apache-2.0")
    (property "MPN" "CR0402-FX-1002GLF")
    (property "Manufacturer" "Bourns")
    (property "Public" "False")
    (property "Sheetfile" "pcie-conn.kicad_sch")
    (property "Sheetname" "PCIe-connector")
    (property "Tolerance" "1%")
    (property "Val" "10k")
    (property "ki_description" "SMD Chip Resistor, 10 kohm, ± 1%, 62.5 mW, 0402 [1005 Metric], Thick Film, General Purpose")
    (property "ki_keywords" "0402, SMT, RESISTOR, PASSIVE")
    (attr smd)
    (fp_text reference "R17" (at -2.75 0.08 90) (layer "F.SilkS")
        (effects (font (size 0.7 0.7) (thickness 0.127)))
    )
    (fp_text value "R_10k_0402" (at 0 1.17 90) (layer "F.Fab")
        (effects (font (size 1 1) (thickness 0.15)))
    )
    (fp_text user "${REFERENCE}" (at 0 0 90) (layer "F.Fab")
        (effects (font (size 0.25 0.25) (thickness 0.04)))
    )
    (fp_text user "License: Apache-2.0" (at -0.95 5.169 -90) (layer "F.Fab") hide
        (effects (font (size 0.7 0.7) (thickness 0.15)) (justify left bottom))
    )
    (fp_text user "Author: Antmicro" (at -0.95 4.169 -90) (layer "F.Fab") hide
        (effects (font (size 0.7 0.7) (thickness 0.15)) (justify left bottom))
    )
    (fp_rect (start -0.925 -0.47) (end 0.925 0.47)
      (stroke (width 0.05) (type default)) (fill none) (layer "F.CrtYd"))
    (fp_rect (start -0.5 -0.25) (end 0.5 0.25)
      (stroke (width 0.15) (type solid)) (fill none) (layer "F.Fab"))
    (pad "1" smd roundrect (at -0.48 0 270) (size 0.59 0.64) (layers "F.Cu" "F.Paste" "F.Mask") (roundrect_rratio 0.25)
      (net 2 "VCC3V3") (pintype "passive"))
    (pad "2" smd roundrect (at 0.48 0 270) (size 0.59 0.64) (layers "F.Cu" "F.Paste" "F.Mask") (roundrect_rratio 0.25)
      (net 380 "Net-(J2-~{CLKREQ})") (pintype "passive"))
  )
)
